(kicad_pcb
	(version 20260206)
	(generator "pcbnew")
	(generator_version "10.0")
	(general
		(thickness 1.6)
		(legacy_teardrops no)
	)
	(paper "A4")
	(title_block
		(title "Bryce Canyon_IOM_IOC_16318-2_OCP.brd")
		(comment 1 "Bryce Canyon / footprints 1-6 of 1605")
	)
	(layers
		(0 "F.Cu" signal "TOP")
		(4 "In1.Cu" signal "L2GND")
		(6 "In2.Cu" signal "L3")
		(8 "In3.Cu" signal "L4VCC")
		(10 "In4.Cu" signal "L5VCC")
		(12 "In5.Cu" signal "L6")
		(14 "In6.Cu" signal "L7GND")
		(2 "B.Cu" signal "BOTTOM")
		(9 "F.Adhes" user "F.Adhesive")
		(11 "B.Adhes" user "B.Adhesive")
		(13 "F.Paste" user "Package Geometry/Pastemask Top")
		(15 "B.Paste" user "Package Geometry/Pastemask Bottom")
		(5 "F.SilkS" user "Ref Des/Silkscreen Top")
		(7 "B.SilkS" user "Ref Des/Silkscreen Bottom")
		(1 "F.Mask" user "Board Geometry/Soldermask Top")
		(3 "B.Mask" user "Board Geometry/Soldermask Bottom")
		(17 "Dwgs.User" user "User.Drawings")
		(19 "Cmts.User" user "User.Comments")
		(21 "Eco1.User" user "User.Eco1")
		(23 "Eco2.User" user "User.Eco2")
		(25 "Edge.Cuts" user "Board Geometry/Outline")
		(27 "Margin" user)
		(31 "F.CrtYd" user "Package Geometry/Place Bound Top")
		(29 "B.CrtYd" user "Package Geometry/Place Bound Bottom")
		(35 "F.Fab" user "Ref Des/Assembly Top")
		(33 "B.Fab" user "Ref Des/Assembly Bottom")
	)
	(footprint ""
		(layer "F.Cu")
		(at 61.294772 -145.496534 -90)
		(property "Reference" "R162"
			(at 0 0 270)
			(layer "F.SilkS")
			(hide yes)
			(effects
				(font
					(size 1.27 1.27)
				)
			)
		)
		(property "Value" "0R2J-2-GP"
			(at 0.064008 -3.993896 270)
			(unlocked yes)
			(layer "F.Fab")
			(hide yes)
			(effects
				(font
					(size 1.016 1.016)
					(thickness 0.1524)
				)
			)
		)
		(property "Device Type" "R402H16"
			(at 0.064008 -5.517896 270)
			(unlocked yes)
			(layer "F.Fab")
			(hide yes)
			(effects
				(font
					(size 1.016 1.016)
					(thickness 0.1524)
				)
			)
		)
		(duplicate_pad_numbers_are_jumpers no)
		(fp_line
			(start -0.508 -0.9398)
			(end -0.508 0.9398)
			(stroke
				(width 0.1524)
				(type default)
			)
			(layer "F.SilkS")
		)
		(fp_line
			(start 0.508 -0.9398)
			(end -0.508 -0.9398)
			(stroke
				(width 0.1524)
				(type default)
			)
			(layer "F.SilkS")
		)
		(fp_rect
			(start -0.508 0.9398)
			(end 0.508 -0.9398)
			(stroke
				(width 0)
				(type default)
			)
			(fill no)
			(layer "F.CrtYd")
		)
		(fp_rect
			(start -0.508 0.9398)
			(end 0.508 -0.9398)
			(stroke
				(width 0)
				(type default)
			)
			(fill no)
			(layer "F.Fab")
		)
		(pad "1" smd custom
			(at 0 -0.4445 270)
			(size 0.1397 0.1397)
			(layers "F.Cu" "F.Mask" "F.Paste")
			(net "I2C_SCC_SDA_OUT")
			(options
				(clearance outline)
				(anchor circle)
			)
			(primitives
				(gr_poly
					(pts
						(arc
							(start -0.1778 -0.2794)
							(mid -0.249642 -0.249642)
							(end -0.2794 -0.1778)
						)
						(arc
							(start -0.2794 0.1778)
							(mid -0.249642 0.249642)
							(end -0.1778 0.2794)
						)
						(arc
							(start 0.1778 0.2794)
							(mid 0.249642 0.249642)
							(end 0.2794 0.1778)
						)
						(arc
							(start 0.2794 -0.1778)
							(mid 0.249642 -0.249642)
							(end 0.1778 -0.2794)
						)
					)
					(width 0)
					(fill yes)
				)
			)
		)
		(pad "2" smd custom
			(at 0 0.4445 270)
			(size 0.1397 0.1397)
			(layers "F.Cu" "F.Mask" "F.Paste")
			(net "BMC_SMB3_DAT")
			(options
				(clearance outline)
				(anchor circle)
			)
			(primitives
				(gr_poly
					(pts
						(arc
							(start -0.1778 -0.2794)
							(mid -0.249642 -0.249642)
							(end -0.2794 -0.1778)
						)
						(arc
							(start -0.2794 0.1778)
							(mid -0.249642 0.249642)
							(end -0.1778 0.2794)
						)
						(arc
							(start 0.1778 0.2794)
							(mid 0.249642 0.249642)
							(end 0.2794 0.1778)
						)
						(arc
							(start 0.2794 -0.1778)
							(mid 0.249642 -0.249642)
							(end 0.1778 -0.2794)
						)
					)
					(width 0)
					(fill yes)
				)
			)
		)
	)
	(footprint ""
		(layer "F.Cu")
		(at 83.358228 -75.749658 90)
		(property "Reference" "VIA10"
			(at 0 0 90)
			(layer "F.SilkS")
			(hide yes)
			(effects
				(font
					(size 1.27 1.27)
				)
			)
		)
		(property "Value" "85OHM-8L-1D6MM-L16L18-GP"
			(at 4.064 0.6096 90)
			(unlocked yes)
			(layer "F.Fab")
			(hide yes)
			(effects
				(font
					(size 1.016 1.016)
					(thickness 0.1524)
				)
			)
		)
		(property "Device Type" "VIA-PCIE-4P-368076"
			(at 4.064 -0.9144 90)
			(unlocked yes)
			(layer "F.Fab")
			(hide yes)
			(effects
				(font
					(size 1.016 1.016)
					(thickness 0.1524)
				)
			)
		)
		(duplicate_pad_numbers_are_jumpers no)
		(fp_rect
			(start -1.8415 0.381)
			(end 1.8415 -0.381)
			(stroke
				(width 0)
				(type default)
			)
			(fill no)
			(layer "F.CrtYd")
		)
		(fp_rect
			(start -1.8415 0.381)
			(end 1.8415 -0.381)
			(stroke
				(width 0)
				(type default)
			)
			(fill no)
			(layer "F.Fab")
		)
		(pad "1" thru_hole circle
			(at -1.4605 0 90)
			(size 0.508 0.508)
			(drill 0.254)
			(layers "*.Cu" "*.Mask")
			(remove_unused_layers no)
			(net "GND")
			(clearance 0.127)
			(thermal_gap 0.127)
		)
		(pad "2" thru_hole circle
			(at -0.4445 0 90)
			(size 0.508 0.508)
			(drill 0.254)
			(layers "*.Cu" "*.Mask")
			(remove_unused_layers no)
			(net "PCIE_IOM_TO_COMP_17_DP")
			(clearance 0.127)
			(thermal_gap 0.127)
		)
		(pad "3" thru_hole circle
			(at 0.4445 0 90)
			(size 0.508 0.508)
			(drill 0.254)
			(layers "*.Cu" "*.Mask")
			(remove_unused_layers no)
			(net "PCIE_IOM_TO_COMP_17_DN")
			(clearance 0.127)
			(thermal_gap 0.127)
		)
		(pad "4" thru_hole circle
			(at 1.4605 0 90)
			(size 0.508 0.508)
			(drill 0.254)
			(layers "*.Cu" "*.Mask")
			(remove_unused_layers no)
			(net "GND")
			(clearance 0.127)
			(thermal_gap 0.127)
		)
	)
	(footprint ""
		(layer "F.Cu")
		(at 184.322212 -45.387768)
		(property "Reference" "R669"
			(at 0 0 0)
			(layer "F.SilkS")
			(hide yes)
			(effects
				(font
					(size 1.27 1.27)
				)
			)
		)
		(property "Value" "10KR2F-2-GP"
			(at 0.064008 -3.993896 0)
			(unlocked yes)
			(layer "F.Fab")
			(hide yes)
			(effects
				(font
					(size 1.016 1.016)
					(thickness 0.1524)
				)
			)
		)
		(property "Device Type" "R402H16"
			(at 0.064008 -5.517896 0)
			(unlocked yes)
			(layer "F.Fab")
			(hide yes)
			(effects
				(font
					(size 1.016 1.016)
					(thickness 0.1524)
				)
			)
		)
		(duplicate_pad_numbers_are_jumpers no)
		(fp_line
			(start -0.508 -0.9398)
			(end -0.508 0.9398)
			(stroke
				(width 0.1524)
				(type default)
			)
			(layer "F.SilkS")
		)
		(fp_line
			(start 0.508 -0.9398)
			(end -0.508 -0.9398)
			(stroke
				(width 0.1524)
				(type default)
			)
			(layer "F.SilkS")
		)
		(fp_rect
			(start -0.508 0.9398)
			(end 0.508 -0.9398)
			(stroke
				(width 0)
				(type default)
			)
			(fill no)
			(layer "F.CrtYd")
		)
		(fp_rect
			(start -0.508 0.9398)
			(end 0.508 -0.9398)
			(stroke
				(width 0)
				(type default)
			)
			(fill no)
			(layer "F.Fab")
		)
		(pad "1" smd custom
			(at 0 -0.4445)
			(size 0.1397 0.1397)
			(layers "F.Cu" "F.Mask" "F.Paste")
			(net "XM_ADDR_2")
			(options
				(clearance outline)
				(anchor circle)
			)
			(primitives
				(gr_poly
					(pts
						(arc
							(start -0.1778 -0.2794)
							(mid -0.249642 -0.249642)
							(end -0.2794 -0.1778)
						)
						(arc
							(start -0.2794 0.1778)
							(mid -0.249642 0.249642)
							(end -0.1778 0.2794)
						)
						(arc
							(start 0.1778 0.2794)
							(mid 0.249642 0.249642)
							(end 0.2794 0.1778)
						)
						(arc
							(start 0.2794 -0.1778)
							(mid 0.249642 -0.249642)
							(end 0.1778 -0.2794)
						)
					)
					(width 0)
					(fill yes)
				)
			)
		)
		(pad "2" smd custom
			(at 0 0.4445)
			(size 0.1397 0.1397)
			(layers "F.Cu" "F.Mask" "F.Paste")
			(net "GND")
			(options
				(clearance outline)
				(anchor circle)
			)
			(primitives
				(gr_poly
					(pts
						(arc
							(start -0.1778 -0.2794)
							(mid -0.249642 -0.249642)
							(end -0.2794 -0.1778)
						)
						(arc
							(start -0.2794 0.1778)
							(mid -0.249642 0.249642)
							(end -0.1778 0.2794)
						)
						(arc
							(start 0.1778 0.2794)
							(mid 0.249642 0.249642)
							(end 0.2794 0.1778)
						)
						(arc
							(start 0.2794 -0.1778)
							(mid 0.249642 -0.249642)
							(end 0.1778 -0.2794)
						)
					)
					(width 0)
					(fill yes)
				)
			)
		)
	)
	(footprint ""
		(layer "F.Cu")
		(at 183.3626 -143.4084 -90)
		(property "Reference" "R475"
			(at 0 0 270)
			(layer "F.SilkS")
			(hide yes)
			(effects
				(font
					(size 1.27 1.27)
				)
			)
		)
		(property "Value" "57K6R2D-GP"
			(at 0.064008 -3.993896 270)
			(unlocked yes)
			(layer "F.Fab")
			(hide yes)
			(effects
				(font
					(size 1.016 1.016)
					(thickness 0.1524)
				)
			)
		)
		(property "Device Type" "R402H16"
			(at 0.064008 -5.517896 270)
			(unlocked yes)
			(layer "F.Fab")
			(hide yes)
			(effects
				(font
					(size 1.016 1.016)
					(thickness 0.1524)
				)
			)
		)
		(duplicate_pad_numbers_are_jumpers no)
		(fp_line
			(start -0.508 -0.9398)
			(end -0.508 0.9398)
			(stroke
				(width 0.1524)
				(type default)
			)
			(layer "F.SilkS")
		)
		(fp_line
			(start 0.508 -0.9398)
			(end -0.508 -0.9398)
			(stroke
				(width 0.1524)
				(type default)
			)
			(layer "F.SilkS")
		)
		(fp_rect
			(start -0.508 0.9398)
			(end 0.508 -0.9398)
			(stroke
				(width 0)
				(type default)
			)
			(fill no)
			(layer "F.CrtYd")
		)
		(fp_rect
			(start -0.508 0.9398)
			(end 0.508 -0.9398)
			(stroke
				(width 0)
				(type default)
			)
			(fill no)
			(layer "F.Fab")
		)
		(pad "1" smd custom
			(at 0 -0.4445 270)
			(size 0.1397 0.1397)
			(layers "F.Cu" "F.Mask" "F.Paste")
			(net "AGND_P5V")
			(options
				(clearance outline)
				(anchor circle)
			)
			(primitives
				(gr_poly
					(pts
						(arc
							(start -0.1778 -0.2794)
							(mid -0.249642 -0.249642)
							(end -0.2794 -0.1778)
						)
						(arc
							(start -0.2794 0.1778)
							(mid -0.249642 0.249642)
							(end -0.1778 0.2794)
						)
						(arc
							(start 0.1778 0.2794)
							(mid 0.249642 0.249642)
							(end 0.2794 0.1778)
						)
						(arc
							(start 0.2794 -0.1778)
							(mid 0.249642 -0.249642)
							(end 0.1778 -0.2794)
						)
					)
					(width 0)
					(fill yes)
				)
			)
		)
		(pad "2" smd custom
			(at 0 0.4445 270)
			(size 0.1397 0.1397)
			(layers "F.Cu" "F.Mask" "F.Paste")
			(net "P5V_TRIP")
			(options
				(clearance outline)
				(anchor circle)
			)
			(primitives
				(gr_poly
					(pts
						(arc
							(start -0.1778 -0.2794)
							(mid -0.249642 -0.249642)
							(end -0.2794 -0.1778)
						)
						(arc
							(start -0.2794 0.1778)
							(mid -0.249642 0.249642)
							(end -0.1778 0.2794)
						)
						(arc
							(start 0.1778 0.2794)
							(mid 0.249642 0.249642)
							(end 0.2794 0.1778)
						)
						(arc
							(start 0.2794 -0.1778)
							(mid 0.249642 -0.249642)
							(end 0.1778 -0.2794)
						)
					)
					(width 0)
					(fill yes)
				)
			)
		)
	)
	(footprint ""
		(layer "F.Cu")
		(at 77.283818 -86.954868 90)
		(property "Reference" "VIA6"
			(at 0 0 90)
			(layer "F.SilkS")
			(hide yes)
			(effects
				(font
					(size 1.27 1.27)
				)
			)
		)
		(property "Value" "85OHM-8L-1D6MM-L16L18-GP"
			(at 4.064 0.6096 90)
			(unlocked yes)
			(layer "F.Fab")
			(hide yes)
			(effects
				(font
					(size 1.016 1.016)
					(thickness 0.1524)
				)
			)
		)
		(property "Device Type" "VIA-PCIE-4P-368076"
			(at 4.064 -0.9144 90)
			(unlocked yes)
			(layer "F.Fab")
			(hide yes)
			(effects
				(font
					(size 1.016 1.016)
					(thickness 0.1524)
				)
			)
		)
		(duplicate_pad_numbers_are_jumpers no)
		(fp_rect
			(start -1.8415 0.381)
			(end 1.8415 -0.381)
			(stroke
				(width 0)
				(type default)
			)
			(fill no)
			(layer "F.CrtYd")
		)
		(fp_rect
			(start -1.8415 0.381)
			(end 1.8415 -0.381)
			(stroke
				(width 0)
				(type default)
			)
			(fill no)
			(layer "F.Fab")
		)
		(pad "1" thru_hole circle
			(at -1.4605 0 90)
			(size 0.508 0.508)
			(drill 0.254)
			(layers "*.Cu" "*.Mask")
			(remove_unused_layers no)
			(net "GND")
			(clearance 0.127)
			(thermal_gap 0.127)
		)
		(pad "2" thru_hole circle
			(at -0.4445 0 90)
			(size 0.508 0.508)
			(drill 0.254)
			(layers "*.Cu" "*.Mask")
			(remove_unused_layers no)
			(net "PCIE_COMP_TO_IOM_21_DP")
			(clearance 0.127)
			(thermal_gap 0.127)
		)
		(pad "3" thru_hole circle
			(at 0.4445 0 90)
			(size 0.508 0.508)
			(drill 0.254)
			(layers "*.Cu" "*.Mask")
			(remove_unused_layers no)
			(net "PCIE_COMP_TO_IOM_21_DN")
			(clearance 0.127)
			(thermal_gap 0.127)
		)
		(pad "4" thru_hole circle
			(at 1.4605 0 90)
			(size 0.508 0.508)
			(drill 0.254)
			(layers "*.Cu" "*.Mask")
			(remove_unused_layers no)
			(net "GND")
			(clearance 0.127)
			(thermal_gap 0.127)
		)
	)
	(footprint ""
		(layer "F.Cu")
		(at 184.6961 -48.1457)
		(property "Reference" "R667"
			(at 0 0 0)
			(layer "F.SilkS")
			(hide yes)
			(effects
				(font
					(size 1.27 1.27)
				)
			)
		)
		(property "Value" "10KR2F-2-GP"
			(at 0.064008 -3.993896 0)
			(unlocked yes)
			(layer "F.Fab")
			(hide yes)
			(effects
				(font
					(size 1.016 1.016)
					(thickness 0.1524)
				)
			)
		)
		(property "Device Type" "R402H16"
			(at 0.064008 -5.517896 0)
			(unlocked yes)
			(layer "F.Fab")
			(hide yes)
			(effects
				(font
					(size 1.016 1.016)
					(thickness 0.1524)
				)
			)
		)
		(duplicate_pad_numbers_are_jumpers no)
		(fp_line
			(start -0.508 -0.9398)
			(end -0.508 0.9398)
			(stroke
				(width 0.1524)
				(type default)
			)
			(layer "F.SilkS")
		)
		(fp_line
			(start 0.508 -0.9398)
			(end -0.508 -0.9398)
			(stroke
				(width 0.1524)
				(type default)
			)
			(layer "F.SilkS")
		)
		(fp_rect
			(start -0.508 0.9398)
			(end 0.508 -0.9398)
			(stroke
				(width 0)
				(type default)
			)
			(fill no)
			(layer "F.CrtYd")
		)
		(fp_rect
			(start -0.508 0.9398)
			(end 0.508 -0.9398)
			(stroke
				(width 0)
				(type default)
			)
			(fill no)
			(layer "F.Fab")
		)
		(pad "1" smd custom
			(at 0 -0.4445)
			(size 0.1397 0.1397)
			(layers "F.Cu" "F.Mask" "F.Paste")
			(net "XM_ADDR_0")
			(options
				(clearance outline)
				(anchor circle)
			)
			(primitives
				(gr_poly
					(pts
						(arc
							(start -0.1778 -0.2794)
							(mid -0.249642 -0.249642)
							(end -0.2794 -0.1778)
						)
						(arc
							(start -0.2794 0.1778)
							(mid -0.249642 0.249642)
							(end -0.1778 0.2794)
						)
						(arc
							(start 0.1778 0.2794)
							(mid 0.249642 0.249642)
							(end 0.2794 0.1778)
						)
						(arc
							(start 0.2794 -0.1778)
							(mid 0.249642 -0.249642)
							(end 0.1778 -0.2794)
						)
					)
					(width 0)
					(fill yes)
				)
			)
		)
		(pad "2" smd custom
			(at 0 0.4445)
			(size 0.1397 0.1397)
			(layers "F.Cu" "F.Mask" "F.Paste")
			(net "GND")
			(options
				(clearance outline)
				(anchor circle)
			)
			(primitives
				(gr_poly
					(pts
						(arc
							(start -0.1778 -0.2794)
							(mid -0.249642 -0.249642)
							(end -0.2794 -0.1778)
						)
						(arc
							(start -0.2794 0.1778)
							(mid -0.249642 0.249642)
							(end -0.1778 0.2794)
						)
						(arc
							(start 0.1778 0.2794)
							(mid 0.249642 0.249642)
							(end 0.2794 0.1778)
						)
						(arc
							(start 0.2794 -0.1778)
							(mid 0.249642 -0.249642)
							(end 0.1778 -0.2794)
						)
					)
					(width 0)
					(fill yes)
				)
			)
		)
	)
)
